# S9S_MB_2U (Grand Teton) — schematic netlist excerpt (pin names and nets, part order shuffled) for the footprints in the layout excerpt that follows; sources: Cadence DE-HDL packaged netlist, KiCad conversion of 03242023_DA0F0TMBIJ0_F0T_Motherboard_J_brd_V01_OCP.brd

J29  SCONN288_ADR50017P130CC  SCONN288_ADR50017-P130CC IO  pkg DDR288S_1-1VXB  page 110
  VIN_BULK0  = P12V_S3_AUX_CPU1_NVDIMM
  RFU0  = TP_CHG_CPU1_DIMM1_FRU_0
  VIN_MGMT  = P3V3_AUX
  HSCL  = I3C_SPD_DDREFGH_CPU1_LVC1_SCL_4
  HSDA  = I3C_SPD_DDREFGH_CPU1_LVC1_SDA
  VSS0  = GND
  DQ0_A  = M_G_CPU1_SA_DQ<0>
  VSS1  = GND
  DQ1_A  = M_G_CPU1_SA_DQ<1>
  VSS2  = GND
  DQS0_A_T  = M_G_CPU1_SA_DQS_DP<0>
  DQS0_A_C  = M_G_CPU1_SA_DQS_DN<0>
  VSS3  = GND
  DQ4_A  = M_G_CPU1_SA_DQ<4>
  VSS4  = GND
  DQ5_A  = M_G_CPU1_SA_DQ<5>
  VSS5  = GND
  DQ8_A  = M_G_CPU1_SA_DQ<8>
  VSS6  = GND
  DQ9_A  = M_G_CPU1_SA_DQ<9>
  VSS7  = GND
  DQS1_A_T  = M_G_CPU1_SA_DQS_DP<1>
  DQS1_A_C  = M_G_CPU1_SA_DQS_DN<1>
  VSS8  = GND
  DQ12_A  = M_G_CPU1_SA_DQ<12>
  VSS9  = GND
  DQ13_A  = M_G_CPU1_SA_DQ<13>
  VSS10  = GND
  DQ16_A  = M_G_CPU1_SA_DQ<16>
  VSS11  = GND
  DQ17_A  = M_G_CPU1_SA_DQ<17>
  VSS12  = GND
  DQS2_A_T  = M_G_CPU1_SA_DQS_DP<2>
  DQS2_A_C  = M_G_CPU1_SA_DQS_DN<2>
  VSS13  = GND
  DQ20_A  = M_G_CPU1_SA_DQ<20>
  VSS14  = GND
  DQ21_A  = M_G_CPU1_SA_DQ<21>
  VSS15  = GND
  DQ24_A  = M_G_CPU1_SA_DQ<24>
  VSS16  = GND
  DQ25_A  = M_G_CPU1_SA_DQ<25>
  VSS17  = GND
  DQS3_A_T  = M_G_CPU1_SA_DQS_DP<3>
  DQS3_A_C  = M_G_CPU1_SA_DQS_DN<3>
  VSS18  = GND
  DQ28_A  = M_G_CPU1_SA_DQ<28>
  VSS19  = GND
  DQ29_A  = M_G_CPU1_SA_DQ<29>
  VSS20  = GND
  CB0_A  = M_G_CPU1_SA_CB<0>
  VSS21  = GND
  CB1_A  = M_G_CPU1_SA_CB<1>
  VSS22  = GND
  DQS4_A_T  = M_G_CPU1_SA_DQS_DP<4>
  DQS4_A_C  = M_G_CPU1_SA_DQS_DN<4>
  VSS23  = GND
  CB4_A  = M_G_CPU1_SA_CB<4>
  VSS24  = GND
  CB5_A  = M_G_CPU1_SA_CB<5>
  VSS25  = GND
  ALERT_N  = M_G_CPU1_ALERT_N
  VSS26  = GND
  CS0_A_N  = M_G_CPU1_SA_CS_N<0>
  VSS27  = GND
  CA0_A  = M_G_CPU1_SA_CA<0>
  VSS28  = GND
  CA2_A  = M_G_CPU1_SA_CA<2>
  VSS29  = GND
  CA4_A  = M_G_CPU1_SA_CA<4>
  VSS30  = GND
  CA6_A  = M_G_CPU1_SA_CA<6>
  VSS31  = GND
  PAR_A  = M_G_CPU1_SA_PAR
  VSS32  = GND
  CA0_B  = M_G_CPU1_SB_CA<0>
  VSS33  = GND
  CA2_B  = M_G_CPU1_SB_CA<2>
  VSS34  = GND
  CA4_B  = M_G_CPU1_SB_CA<4>
  VSS35  = GND
  CA6_B  = M_G_CPU1_SB_CA<6>
  VSS36  = GND
  CS0_B_N  = M_G_CPU1_SB_CS_N<0>
  VSS37  = GND
  \lbd||rsp_a_n\  = M_G_CPU1_SA_RSP<0>
  \lbs||rsp_b_n\  = M_G_CPU1_SB_RSP<0>
  VSS38  = GND
  CB4_B  = M_G_CPU1_SB_CB<4>
  VSS39  = GND
  CB5_B  = M_G_CPU1_SB_CB<5>
  VSS40  = GND
  \dqs9_b_t||tdqs9_b_t||dbi4_b_n\  = M_G_CPU1_SB_DQS_DP<9>
  \dqs9_b_c||tdqs9_b_c\  = M_G_CPU1_SB_DQS_DN<9>
  VSS41  = GND
  CB0_B  = M_G_CPU1_SB_CB<0>
  VSS42  = GND
  CB1_B  = M_G_CPU1_SB_CB<1>
  VSS43  = GND
  DQ0_B  = M_G_CPU1_SB_DQ<0>
  VSS44  = GND
  DQ1_B  = M_G_CPU1_SB_DQ<1>
  VSS45  = GND
  DQS0_B_T  = M_G_CPU1_SB_DQS_DP<0>
  DQS0_B_C  = M_G_CPU1_SB_DQS_DN<0>
  VSS46  = GND
  DQ4_B  = M_G_CPU1_SB_DQ<4>
  VSS47  = GND
  DQ5_B  = M_G_CPU1_SB_DQ<5>
  VSS48  = GND
  DQ8_B  = M_G_CPU1_SB_DQ<8>
  VSS49  = GND
  DQ9_B  = M_G_CPU1_SB_DQ<9>
  VSS50  = GND
  DQS1_B_T  = M_G_CPU1_SB_DQS_DP<1>
  DQS1_B_C  = M_G_CPU1_SB_DQS_DN<1>
  VSS51  = GND
  DQ12_B  = M_G_CPU1_SB_DQ<12>
  VSS52  = GND
  DQ13_B  = M_G_CPU1_SB_DQ<13>
  VSS53  = GND
  DQ16_B  = M_G_CPU1_SB_DQ<16>
  VSS54  = GND
  DQ17_B  = M_G_CPU1_SB_DQ<17>
  VSS55  = GND
  DQS2_B_T  = M_G_CPU1_SB_DQS_DP<2>
  DQS2_B_C  = M_G_CPU1_SB_DQS_DN<2>
  VSS56  = GND
  DQ20_B  = M_G_CPU1_SB_DQ<20>
  VSS57  = GND
  DQ21_B  = M_G_CPU1_SB_DQ<21>
  VSS58  = GND
  DQ24_B  = M_G_CPU1_SB_DQ<24>
  VSS59  = GND
  DQ25_B  = M_G_CPU1_SB_DQ<25>
  VSS60  = GND
  DQS3_B_T  = M_G_CPU1_SB_DQS_DP<3>
  DQS3_B_C  = M_G_CPU1_SB_DQS_DN<3>
  VSS61  = GND
  DQ28_B  = M_G_CPU1_SB_DQ<28>
  VSS62  = GND
  DQ29_B  = M_G_CPU1_SB_DQ<29>
  VSS63  = GND
  RFU1  = TP_CHG_CPU1_DIMM1_FRU_1
  VIN_BULK1  = P12V_S3_AUX_CPU1_NVDIMM
  VIN_BULK2  = P12V_S3_AUX_CPU1_NVDIMM
  \pwr_good||fail_n\  = PWRGD_CHG_CPU1_DIMM1
  HSA  = PD_CHG_CPU1_DIMM1_SAA
  RFU2  = TP_CHG_CPU1_DIMM1_FRU_2
  RFU3  = TP_CHG_CPU1_DIMM1_FRU_3
  VSS64  = GND
  DQ2_A  = M_G_CPU1_SA_DQ<2>
  VSS65  = GND
  DQ3_A  = M_G_CPU1_SA_DQ<3>
  VSS66  = GND
  \dqs5_a_c||tdqs5_a_c||dqs5_a_t||tdqs5_a_t\  = M_G_CPU1_SA_DQS_DN<5>
  \dqs5_a_t||tdqs5_a_t\  = M_G_CPU1_SA_DQS_DP<5>
  VSS67  = GND
  DQ6_A  = M_G_CPU1_SA_DQ<6>
  VSS68  = GND
  DQ7_A  = M_G_CPU1_SA_DQ<7>
  VSS69  = GND
  DQ10_A  = M_G_CPU1_SA_DQ<10>
  VSS70  = GND
  DQ11_A  = M_G_CPU1_SA_DQ<11>
  VSS71  = GND
  \dqs6_a_c||tdqs6_a_c||dqs6_a_t||tdqs6_a_t\  = M_G_CPU1_SA_DQS_DN<6>
  \dqs6_a_t||tdqs6_a_t\  = M_G_CPU1_SA_DQS_DP<6>
  VSS72  = GND
  DQ14_A  = M_G_CPU1_SA_DQ<14>
  VSS73  = GND
  DQ15_A  = M_G_CPU1_SA_DQ<15>
  VSS74  = GND
  DQ18_A  = M_G_CPU1_SA_DQ<18>
  VSS75  = GND
  DQ19_A  = M_G_CPU1_SA_DQ<19>
  VSS76  = GND
  \dqs7_a_c||tdqs7_a_c\  = M_G_CPU1_SA_DQS_DN<7>
  \dqs7_a_t||tdqs7_a_t\  = M_G_CPU1_SA_DQS_DP<7>
  VSS77  = GND
  DQ22_A  = M_G_CPU1_SA_DQ<22>
  VSS78  = GND
  DQ23_A  = M_G_CPU1_SA_DQ<23>
  VSS79  = GND
  DQ26_A  = M_G_CPU1_SA_DQ<26>
  VSS80  = GND
  DQ27_A  = M_G_CPU1_SA_DQ<27>
  VSS81  = GND
  \dqs8_a_c||tdqs8_a_c\  = M_G_CPU1_SA_DQS_DN<8>
  \dqs8_a_t||tdqs8_a_t\  = M_G_CPU1_SA_DQS_DP<8>
  VSS82  = GND
  DQ30_A  = M_G_CPU1_SA_DQ<30>
  VSS83  = GND
  DQ31_A  = M_G_CPU1_SA_DQ<31>
  VSS84  = GND
  CB2_A  = M_G_CPU1_SA_CB<2>
  VSS85  = GND
  CB3_A  = M_G_CPU1_SA_CB<3>
  VSS86  = GND
  \dqs9_a_c||tdqs9_a_c\  = M_G_CPU1_SA_DQS_DN<9>
  \dqs9_a_t||tdqs9_a_t\  = M_G_CPU1_SA_DQS_DP<9>
  VSS87  = GND
  CB6_A  = M_G_CPU1_SA_CB<6>
  VSS88  = GND
  CB7_A  = M_G_CPU1_SA_CB<7>
  VSS89  = GND
  RESET_N  = RST_M_GH_CPU1_FPGA_N
  VSS90  = GND
  CS1_A_N  = M_G_CPU1_SA_CS_N<1>
  VSS91  = GND
  CA1_A  = M_G_CPU1_SA_CA<1>
  VSS92  = GND
  CA3_A  = M_G_CPU1_SA_CA<3>
  VSS93  = GND
  CA5_A  = M_G_CPU1_SA_CA<5>
  VSS94  = GND
  CK_T  = M_G_CPU1_CLK_DP<0>
  CK_C  = M_G_CPU1_CLK_DN<0>
  VSS95  = GND
  RFU4  = TP_CHG_CPU1_DIMM1_FRU_4
  CA1_B  = M_G_CPU1_SB_CA<1>
  VSS96  = GND
  CA3_B  = M_G_CPU1_SB_CA<3>
  VSS97  = GND
  CA5_B  = M_G_CPU1_SB_CA<5>
  VSS98  = GND
  PAR_B  = M_G_CPU1_SB_PAR
  VSS99  = GND
  CS1_B_N  = M_G_CPU1_SB_CS_N<1>
  VSS100  = GND
  RFU5  = TP_CHG_CPU1_DIMM1_FRU_5
  RFU6  = TP_CHG_CPU1_DIMM1_FRU_6
  VSS101  = GND
  CB6_B  = M_G_CPU1_SB_CB<6>
  VSS102  = GND
  CB7_B  = M_G_CPU1_SB_CB<7>
  VSS103  = GND
  DQS4_B_C  = M_G_CPU1_SB_DQS_DN<4>
  DQS4_B_T  = M_G_CPU1_SB_DQS_DP<4>
  VSS104  = GND
  CB2_B  = M_G_CPU1_SB_CB<2>
  VSS105  = GND
  CB3_B  = M_G_CPU1_SB_CB<3>
  VSS106  = GND
  DQ2_B  = M_G_CPU1_SB_DQ<2>
  VSS107  = GND
  DQ3_B  = M_G_CPU1_SB_DQ<3>
  VSS108  = GND
  \dqs5_b_c||tdqs5_b_c\  = M_G_CPU1_SB_DQS_DN<5>
  \dqs5_b_t||tdqs5_b_t\  = M_G_CPU1_SB_DQS_DP<5>
  VSS109  = GND
  DQ6_B  = M_G_CPU1_SB_DQ<6>
  VSS110  = GND
  DQ7_B  = M_G_CPU1_SB_DQ<7>
  VSS111  = GND
  DQ10_B  = M_G_CPU1_SB_DQ<10>
  VSS112  = GND
  DQ11_B  = M_G_CPU1_SB_DQ<11>
  VSS113  = GND
  \dqs6_b_c||tdqs6_b_c\  = M_G_CPU1_SB_DQS_DN<6>
  \dqs6_b_t||tdqs6_b_t\  = M_G_CPU1_SB_DQS_DP<6>
  VSS114  = GND
  DQ14_B  = M_G_CPU1_SB_DQ<14>
  VSS115  = GND
  DQ15_B  = M_G_CPU1_SB_DQ<15>
  VSS116  = GND
  DQ18_B  = M_G_CPU1_SB_DQ<18>
  VSS117  = GND
  DQ19_B  = M_G_CPU1_SB_DQ<19>
  VSS118  = GND
  \dqs7_b_c||tdqs7_b_c\  = M_G_CPU1_SB_DQS_DN<7>
  \dqs7_b_t||tdqs7_b_t\  = M_G_CPU1_SB_DQS_DP<7>
  VSS119  = GND
  DQ22_B  = M_G_CPU1_SB_DQ<22>
  VSS120  = GND
  DQ23_B  = M_G_CPU1_SB_DQ<23>
  VSS121  = GND
  DQ26_B  = M_G_CPU1_SB_DQ<26>
  VSS122  = GND
  DQ27_B  = M_G_CPU1_SB_DQ<27>
  VSS123  = GND
  \dqs8_b_c||tdqs8_b_c\  = M_G_CPU1_SB_DQS_DN<8>
  \dqs8_b_t||tdqs8_b_t\  = M_G_CPU1_SB_DQS_DP<8>
  VSS124  = GND
  DQ30_B  = M_G_CPU1_SB_DQ<30>
  VSS125  = GND
  DQ31_B  = M_G_CPU1_SB_DQ<31>
  VSS126  = GND
  G1  = GND
  G2  = GND
  G3  = GND

(kicad_pcb
	(version 20260206)
	(generator "pcbnew")
	(generator_version "10.0")
	(general
		(thickness 1.6)
		(legacy_teardrops no)
	)
	(paper "A4")
	(title_block
		(title "03242023_DA0F0TMBIJ0_F0T_Motherboard_J_brd_V01_OCP.brd")
		(comment 1 "Grand Teton / footprint 2874 of 6105 (J29), pads 275-291 of 291")
	)
	(layers
		(0 "F.Cu" signal "TOP")
		(4 "In1.Cu" signal "GND")
		(6 "In2.Cu" signal "IN1")
		(8 "In3.Cu" signal "GND1")
		(10 "In4.Cu" signal "IN2")
		(12 "In5.Cu" signal "GND2")
		(14 "In6.Cu" signal "IN3")
		(16 "In7.Cu" signal "GND3")
		(18 "In8.Cu" signal "VCC")
		(20 "In9.Cu" signal "VCC1")
		(22 "In10.Cu" signal "GND4")
		(24 "In11.Cu" signal "IN4")
		(26 "In12.Cu" signal "GND5")
		(28 "In13.Cu" signal "IN5")
		(30 "In14.Cu" signal "GND6")
		(32 "In15.Cu" signal "IN6")
		(34 "In16.Cu" signal "GND7")
		(2 "B.Cu" signal "BOTTOM")
		(9 "F.Adhes" user "F.Adhesive")
		(11 "B.Adhes" user "B.Adhesive")
		(13 "F.Paste" user "Package Geometry/Pastemask Top")
		(15 "B.Paste" user "Package Geometry/Pastemask Bottom")
		(5 "F.SilkS" user "Ref Des/Silkscreen Top")
		(7 "B.SilkS" user "Ref Des/Silkscreen Bottom")
		(1 "F.Mask" user "Board Geometry/Soldermask Top")
		(3 "B.Mask" user "Board Geometry/Soldermask Bottom")
		(17 "Dwgs.User" user "User.Drawings")
		(19 "Cmts.User" user "User.Comments")
		(21 "Eco1.User" user "User.Eco1")
		(23 "Eco2.User" user "User.Eco2")
		(25 "Edge.Cuts" user "Board Geometry/Outline")
		(27 "Margin" user)
		(31 "F.CrtYd" user "Package Geometry/Place Bound Top")
		(29 "B.CrtYd" user "Package Geometry/Place Bound Bottom")
		(35 "F.Fab" user "Ref Des/Assembly Top")
		(33 "B.Fab" user "Ref Des/Assembly Bottom")
	)
	(footprint ""
		(layer "F.Cu")
		(at 198.58228 -258.091686)
		(property "Reference" "J29"
			(at -3.683 -81.702148 0)
			(unlocked yes)
			(layer "F.SilkS")
			(effects
				(font
					(size 0.7874 0.5842)
					(thickness 0.1524)
				)
				(justify left)
			)
		)
		(property "Value" ""
			(at 0 0 0)
			(layer "F.Fab")
			(effects
				(font
					(size 1.27 1.27)
				)
			)
		)
		(duplicate_pad_numbers_are_jumpers no)
		(pad "275" smd rect
			(at 2.050034 52.274978 270)
			(size 0.519938 1.4986)
			(layers "F.Cu" "F.Mask" "F.Paste")
			(net "GND")
		)
		(pad "276" smd rect
			(at 2.050034 53.125116 270)
			(size 0.519938 1.4986)
			(layers "F.Cu" "F.Mask" "F.Paste")
			(net "M_G_CPU1_SB_DQ<23>")
		)
		(pad "277" smd rect
			(at 2.050034 53.975 270)
			(size 0.519938 1.4986)
			(layers "F.Cu" "F.Mask" "F.Paste")
			(net "GND")
		)
		(pad "278" smd rect
			(at 2.050034 54.824884 270)
			(size 0.519938 1.4986)
			(layers "F.Cu" "F.Mask" "F.Paste")
			(net "M_G_CPU1_SB_DQ<26>")
		)
		(pad "279" smd rect
			(at 2.050034 55.675022 270)
			(size 0.519938 1.4986)
			(layers "F.Cu" "F.Mask" "F.Paste")
			(net "GND")
		)
		(pad "280" smd rect
			(at 2.050034 56.524906 270)
			(size 0.519938 1.4986)
			(layers "F.Cu" "F.Mask" "F.Paste")
			(net "M_G_CPU1_SB_DQ<27>")
		)
		(pad "281" smd rect
			(at 2.050034 57.375044 270)
			(size 0.519938 1.4986)
			(layers "F.Cu" "F.Mask" "F.Paste")
			(net "GND")
		)
		(pad "282" smd rect
			(at 2.050034 58.224928 270)
			(size 0.519938 1.4986)
			(layers "F.Cu" "F.Mask" "F.Paste")
			(net "M_G_CPU1_SB_DQS_DN<8>")
		)
		(pad "283" smd rect
			(at 2.050034 59.075066 270)
			(size 0.519938 1.4986)
			(layers "F.Cu" "F.Mask" "F.Paste")
			(net "M_G_CPU1_SB_DQS_DP<8>")
		)
		(pad "284" smd rect
			(at 2.050034 59.92495 270)
			(size 0.519938 1.4986)
			(layers "F.Cu" "F.Mask" "F.Paste")
			(net "GND")
		)
		(pad "285" smd rect
			(at 2.050034 60.775088 270)
			(size 0.519938 1.4986)
			(layers "F.Cu" "F.Mask" "F.Paste")
			(net "M_G_CPU1_SB_DQ<30>")
		)
		(pad "286" smd rect
			(at 2.050034 61.624972 270)
			(size 0.519938 1.4986)
			(layers "F.Cu" "F.Mask" "F.Paste")
			(net "GND")
		)
		(pad "287" smd rect
			(at 2.050034 62.47511 270)
			(size 0.519938 1.4986)
			(layers "F.Cu" "F.Mask" "F.Paste")
			(net "M_G_CPU1_SB_DQ<31>")
		)
		(pad "288" smd rect
			(at 2.050034 63.324994 270)
			(size 0.519938 1.4986)
			(layers "F.Cu" "F.Mask" "F.Paste")
			(net "GND")
		)
		(pad "G1" thru_hole oval
			(at 0 -68.97497)
			(size 2.8194 1.5748)
			(drill oval 2.4384 1.1938)
			(layers "*.Cu" "*.Mask")
			(remove_unused_layers no)
			(net "GND")
			(clearance 0.127)
			(thermal_gap 0.127)
		)
		(pad "G2" thru_hole oval
			(at 0 3.875024)
			(size 2.8194 1.5748)
			(drill oval 2.4384 1.1938)
			(layers "*.Cu" "*.Mask")
			(remove_unused_layers no)
			(net "GND")
			(clearance 0.127)
			(thermal_gap 0.127)
		)
		(pad "G3" thru_hole oval
			(at 0 68.97497)
			(size 2.8194 1.5748)
			(drill oval 2.4384 1.1938)
			(layers "*.Cu" "*.Mask")
			(remove_unused_layers no)
			(net "GND")
			(clearance 0.127)
			(thermal_gap 0.127)
		)
	)
)
